# T6G (Grand Teton) — schematic netlist excerpt (pin names and nets, part order shuffled) for the footprints in the layout excerpt that follows; sources: Cadence DE-HDL packaged netlist, KiCad conversion of 04192023_DAF0TMB3IC0_F0TG_MB_C_brd_V02_OCP.brd

PR86  Q_RES  8.87K 1% EMPTY  pkg 0402LF  page 202 : A = PVDDCR_CPU1_P0_LSET3 ; B = GND
PC309_5  Q_CAP  0.1UF 25V 10% X7R  pkg 0402  page 213 : A = SW_P12V_AUX_PVDDCR_CPU0_P1_FLT ; B = GND

(kicad_pcb
	(version 20260206)
	(generator "pcbnew")
	(generator_version "10.0")
	(general
		(thickness 1.6)
		(legacy_teardrops no)
	)
	(paper "A4")
	(title_block
		(title "04192023_DAF0TMB3IC0_F0TG_MB_C_brd_V02_OCP.brd")
		(comment 1 "Grand Teton / footprints 259-260 of 8354")
	)
	(layers
		(0 "F.Cu" signal "TOP")
		(4 "In1.Cu" signal "GND")
		(6 "In2.Cu" signal "IN1")
		(8 "In3.Cu" signal "GND1")
		(10 "In4.Cu" signal "IN2")
		(12 "In5.Cu" signal "GND2")
		(14 "In6.Cu" signal "IN3")
		(16 "In7.Cu" signal "GND3")
		(18 "In8.Cu" signal "VCC")
		(20 "In9.Cu" signal "VCC1")
		(22 "In10.Cu" signal "GND4")
		(24 "In11.Cu" signal "IN4")
		(26 "In12.Cu" signal "GND5")
		(28 "In13.Cu" signal "IN5")
		(30 "In14.Cu" signal "GND6")
		(32 "In15.Cu" signal "IN6")
		(34 "In16.Cu" signal "GND7")
		(2 "B.Cu" signal "BOTTOM")
		(9 "F.Adhes" user "F.Adhesive")
		(11 "B.Adhes" user "B.Adhesive")
		(13 "F.Paste" user "Package Geometry/Pastemask Top")
		(15 "B.Paste" user "Package Geometry/Pastemask Bottom")
		(5 "F.SilkS" user "Ref Des/Silkscreen Top")
		(7 "B.SilkS" user "Ref Des/Silkscreen Bottom")
		(1 "F.Mask" user "Board Geometry/Soldermask Top")
		(3 "B.Mask" user "Board Geometry/Soldermask Bottom")
		(17 "Dwgs.User" user "User.Drawings")
		(19 "Cmts.User" user "User.Comments")
		(21 "Eco1.User" user "User.Eco1")
		(23 "Eco2.User" user "User.Eco2")
		(25 "Edge.Cuts" user "Board Geometry/Outline")
		(27 "Margin" user)
		(31 "F.CrtYd" user "Package Geometry/Place Bound Top")
		(29 "B.CrtYd" user "Package Geometry/Place Bound Bottom")
		(35 "F.Fab" user "Ref Des/Assembly Top")
		(33 "B.Fab" user "Ref Des/Assembly Bottom")
	)
	(footprint ""
		(layer "F.Cu")
		(at 72.099678 -171.2341)
		(property "Reference" "PC309_5"
			(at 0 0 0)
			(layer "F.SilkS")
			(hide yes)
			(effects
				(font
					(size 1.27 1.27)
				)
			)
		)
		(property "Value" ""
			(at 0 0 0)
			(layer "F.Fab")
			(effects
				(font
					(size 1.27 1.27)
				)
			)
		)
		(duplicate_pad_numbers_are_jumpers no)
		(fp_line
			(start -0.7874 -0.4064)
			(end 0.7874 -0.4064)
			(stroke
				(width 0.1524)
				(type default)
			)
			(layer "F.SilkS")
		)
		(fp_line
			(start -0.7874 0.4064)
			(end -0.7874 -0.4064)
			(stroke
				(width 0.1524)
				(type default)
			)
			(layer "F.SilkS")
		)
		(fp_line
			(start 0.7874 -0.4064)
			(end 0.7874 0.4064)
			(stroke
				(width 0.1524)
				(type default)
			)
			(layer "F.SilkS")
		)
		(fp_line
			(start 0.7874 0.4064)
			(end -0.7874 0.4064)
			(stroke
				(width 0.1524)
				(type default)
			)
			(layer "F.SilkS")
		)
		(fp_line
			(start -0.67945 -0.305054)
			(end -0.12065 -0.305054)
			(stroke
				(width 0.1)
				(type default)
			)
			(layer "F.Fab")
		)
		(fp_line
			(start -0.67945 0.3048)
			(end -0.67945 -0.305054)
			(stroke
				(width 0.1)
				(type default)
			)
			(layer "F.Fab")
		)
		(fp_line
			(start -0.12065 -0.305054)
			(end -0.12065 -0.2794)
			(stroke
				(width 0.1)
				(type default)
			)
			(layer "F.Fab")
		)
		(fp_line
			(start -0.12065 -0.2794)
			(end 0.12065 -0.2794)
			(stroke
				(width 0.1)
				(type default)
			)
			(layer "F.Fab")
		)
		(fp_line
			(start -0.12065 0.2794)
			(end -0.12065 0.3048)
			(stroke
				(width 0.1)
				(type default)
			)
			(layer "F.Fab")
		)
		(fp_line
			(start -0.12065 0.3048)
			(end -0.67945 0.3048)
			(stroke
				(width 0.1)
				(type default)
			)
			(layer "F.Fab")
		)
		(fp_line
			(start 0.120396 0.2794)
			(end -0.12065 0.2794)
			(stroke
				(width 0.1)
				(type default)
			)
			(layer "F.Fab")
		)
		(fp_line
			(start 0.120396 0.3048)
			(end 0.120396 0.2794)
			(stroke
				(width 0.1)
				(type default)
			)
			(layer "F.Fab")
		)
		(fp_line
			(start 0.12065 -0.3048)
			(end 0.67945 -0.3048)
			(stroke
				(width 0.1)
				(type default)
			)
			(layer "F.Fab")
		)
		(fp_line
			(start 0.12065 -0.2794)
			(end 0.12065 -0.3048)
			(stroke
				(width 0.1)
				(type default)
			)
			(layer "F.Fab")
		)
		(fp_line
			(start 0.67945 -0.3048)
			(end 0.67945 0.3048)
			(stroke
				(width 0.1)
				(type default)
			)
			(layer "F.Fab")
		)
		(fp_line
			(start 0.67945 0.3048)
			(end 0.120396 0.3048)
			(stroke
				(width 0.1)
				(type default)
			)
			(layer "F.Fab")
		)
		(pad "1" smd circle
			(at -0.40005 0)
			(size 0 0)
			(layers "F.Cu" "F.Mask" "F.Paste")
			(net "SW_P12V_AUX_PVDDCR_CPU0_P1_FLT")
		)
		(pad "2" smd circle
			(at 0.40005 0)
			(size 0 0)
			(layers "F.Cu" "F.Mask" "F.Paste")
			(net "GND")
		)
	)
	(footprint ""
		(layer "F.Cu")
		(at 317.041276 -340.206838)
		(property "Reference" "PR86"
			(at 0 0 0)
			(layer "F.SilkS")
			(hide yes)
			(effects
				(font
					(size 1.27 1.27)
				)
			)
		)
		(property "Value" ""
			(at 0 0 0)
			(layer "F.Fab")
			(effects
				(font
					(size 1.27 1.27)
				)
			)
		)
		(duplicate_pad_numbers_are_jumpers no)
		(fp_line
			(start -0.7874 -0.4064)
			(end 0.7874 -0.4064)
			(stroke
				(width 0.1524)
				(type default)
			)
			(layer "F.SilkS")
		)
		(fp_line
			(start -0.7874 0.4064)
			(end -0.7874 -0.4064)
			(stroke
				(width 0.1524)
				(type default)
			)
			(layer "F.SilkS")
		)
		(fp_line
			(start 0.7874 -0.4064)
			(end 0.7874 0.4064)
			(stroke
				(width 0.1524)
				(type default)
			)
			(layer "F.SilkS")
		)
		(fp_line
			(start 0.7874 0.4064)
			(end -0.7874 0.4064)
			(stroke
				(width 0.1524)
				(type default)
			)
			(layer "F.SilkS")
		)
		(fp_line
			(start -0.67945 -0.305054)
			(end -0.12065 -0.305054)
			(stroke
				(width 0.1)
				(type default)
			)
			(layer "F.Fab")
		)
		(fp_line
			(start -0.67945 0.3048)
			(end -0.67945 -0.305054)
			(stroke
				(width 0.1)
				(type default)
			)
			(layer "F.Fab")
		)
		(fp_line
			(start -0.12065 -0.305054)
			(end -0.12065 -0.2794)
			(stroke
				(width 0.1)
				(type default)
			)
			(layer "F.Fab")
		)
		(fp_line
			(start -0.12065 -0.2794)
			(end 0.12065 -0.2794)
			(stroke
				(width 0.1)
				(type default)
			)
			(layer "F.Fab")
		)
		(fp_line
			(start -0.12065 0.2794)
			(end -0.12065 0.3048)
			(stroke
				(width 0.1)
				(type default)
			)
			(layer "F.Fab")
		)
		(fp_line
			(start -0.12065 0.3048)
			(end -0.67945 0.3048)
			(stroke
				(width 0.1)
				(type default)
			)
			(layer "F.Fab")
		)
		(fp_line
			(start 0.120396 0.2794)
			(end -0.12065 0.2794)
			(stroke
				(width 0.1)
				(type default)
			)
			(layer "F.Fab")
		)
		(fp_line
			(start 0.120396 0.3048)
			(end 0.120396 0.2794)
			(stroke
				(width 0.1)
				(type default)
			)
			(layer "F.Fab")
		)
		(fp_line
			(start 0.12065 -0.3048)
			(end 0.67945 -0.3048)
			(stroke
				(width 0.1)
				(type default)
			)
			(layer "F.Fab")
		)
		(fp_line
			(start 0.12065 -0.2794)
			(end 0.12065 -0.3048)
			(stroke
				(width 0.1)
				(type default)
			)
			(layer "F.Fab")
		)
		(fp_line
			(start 0.67945 -0.3048)
			(end 0.67945 0.3048)
			(stroke
				(width 0.1)
				(type default)
			)
			(layer "F.Fab")
		)
		(fp_line
			(start 0.67945 0.3048)
			(end 0.120396 0.3048)
			(stroke
				(width 0.1)
				(type default)
			)
			(layer "F.Fab")
		)
		(pad "1" smd circle
			(at -0.40005 0)
			(size 0 0)
			(layers "F.Cu" "F.Mask" "F.Paste")
			(net "PVDDCR_CPU1_P0_LSET3")
		)
		(pad "2" smd circle
			(at 0.40005 0)
			(size 0 0)
			(layers "F.Cu" "F.Mask" "F.Paste")
			(net "GND")
		)
	)
)
